# SCM (Grand Teton) — schematic netlist excerpt (pin names and nets, part order shuffled) for the footprints in the layout excerpt that follows; sources: Cadence DE-HDL packaged netlist, KiCad conversion of 12092022_DA0F0TMDCD0_F0T_Management_Board_D_brd_V3_OCP.brd

C103  Q_CAP  0.1UF 25V 10% X7R  pkg 0402  page 16 : A = P1V2_AUX ; B = GND

(kicad_pcb
	(version 20260206)
	(generator "pcbnew")
	(generator_version "10.0")
	(general
		(thickness 1.6)
		(legacy_teardrops no)
	)
	(paper "A4")
	(title_block
		(title "12092022_DA0F0TMDCD0_F0T_Management_Board_D_brd_V3_OCP.brd")
		(comment 1 "Grand Teton / footprints 915-915 of 1440")
	)
	(layers
		(0 "F.Cu" signal "TOP")
		(4 "In1.Cu" signal "GND")
		(6 "In2.Cu" signal "IN1")
		(8 "In3.Cu" signal "GND1")
		(10 "In4.Cu" signal "IN2")
		(12 "In5.Cu" signal "VCC")
		(14 "In6.Cu" signal "VCC1")
		(16 "In7.Cu" signal "IN3")
		(18 "In8.Cu" signal "GND2")
		(20 "In9.Cu" signal "IN4")
		(22 "In10.Cu" signal "GND3")
		(2 "B.Cu" signal "BOTTOM")
		(9 "F.Adhes" user "F.Adhesive")
		(11 "B.Adhes" user "B.Adhesive")
		(13 "F.Paste" user "Package Geometry/Pastemask Top")
		(15 "B.Paste" user "Package Geometry/Pastemask Bottom")
		(5 "F.SilkS" user "Ref Des/Silkscreen Top")
		(7 "B.SilkS" user "Ref Des/Silkscreen Bottom")
		(1 "F.Mask" user "Board Geometry/Soldermask Top")
		(3 "B.Mask" user "Board Geometry/Soldermask Bottom")
		(17 "Dwgs.User" user "User.Drawings")
		(19 "Cmts.User" user "User.Comments")
		(21 "Eco1.User" user "User.Eco1")
		(23 "Eco2.User" user "User.Eco2")
		(25 "Edge.Cuts" user "Board Geometry/Outline")
		(27 "Margin" user)
		(31 "F.CrtYd" user "Package Geometry/Place Bound Top")
		(29 "B.CrtYd" user "Package Geometry/Place Bound Bottom")
		(35 "F.Fab" user "Ref Des/Assembly Top")
		(33 "B.Fab" user "Ref Des/Assembly Bottom")
	)
	(footprint ""
		(layer "B.Cu")
		(at 50.974244 -49.38141 180)
		(property "Reference" "C103"
			(at 0 0 0)
			(layer "B.SilkS")
			(hide yes)
			(effects
				(font
					(size 1.27 1.27)
				)
				(justify mirror)
			)
		)
		(property "Value" ""
			(at 0 0 0)
			(layer "B.Fab")
			(effects
				(font
					(size 1.27 1.27)
				)
				(justify mirror)
			)
		)
		(duplicate_pad_numbers_are_jumpers no)
		(fp_line
			(start 0.7874 0.4064)
			(end 0.7874 -0.4064)
			(stroke
				(width 0.1524)
				(type default)
			)
			(layer "B.SilkS")
		)
		(fp_line
			(start 0.7874 -0.4064)
			(end -0.7874 -0.4064)
			(stroke
				(width 0.1524)
				(type default)
			)
			(layer "B.SilkS")
		)
		(fp_line
			(start -0.7874 0.4064)
			(end 0.7874 0.4064)
			(stroke
				(width 0.1524)
				(type default)
			)
			(layer "B.SilkS")
		)
		(fp_line
			(start -0.7874 -0.4064)
			(end -0.7874 0.4064)
			(stroke
				(width 0.1524)
				(type default)
			)
			(layer "B.SilkS")
		)
		(fp_line
			(start 0.67945 0.3048)
			(end 0.67945 -0.305054)
			(stroke
				(width 0.1)
				(type default)
			)
			(layer "B.Fab")
		)
		(fp_line
			(start 0.67945 -0.305054)
			(end 0.12065 -0.305054)
			(stroke
				(width 0.1)
				(type default)
			)
			(layer "B.Fab")
		)
		(fp_line
			(start 0.12065 0.3048)
			(end 0.67945 0.3048)
			(stroke
				(width 0.1)
				(type default)
			)
			(layer "B.Fab")
		)
		(fp_line
			(start 0.12065 0.2794)
			(end 0.12065 0.3048)
			(stroke
				(width 0.1)
				(type default)
			)
			(layer "B.Fab")
		)
		(fp_line
			(start 0.12065 -0.2794)
			(end -0.12065 -0.2794)
			(stroke
				(width 0.1)
				(type default)
			)
			(layer "B.Fab")
		)
		(fp_line
			(start 0.12065 -0.305054)
			(end 0.12065 -0.2794)
			(stroke
				(width 0.1)
				(type default)
			)
			(layer "B.Fab")
		)
		(fp_line
			(start -0.120396 0.3048)
			(end -0.120396 0.2794)
			(stroke
				(width 0.1)
				(type default)
			)
			(layer "B.Fab")
		)
		(fp_line
			(start -0.120396 0.2794)
			(end 0.12065 0.2794)
			(stroke
				(width 0.1)
				(type default)
			)
			(layer "B.Fab")
		)
		(fp_line
			(start -0.12065 -0.2794)
			(end -0.12065 -0.3048)
			(stroke
				(width 0.1)
				(type default)
			)
			(layer "B.Fab")
		)
		(fp_line
			(start -0.12065 -0.3048)
			(end -0.67945 -0.3048)
			(stroke
				(width 0.1)
				(type default)
			)
			(layer "B.Fab")
		)
		(fp_line
			(start -0.67945 0.3048)
			(end -0.120396 0.3048)
			(stroke
				(width 0.1)
				(type default)
			)
			(layer "B.Fab")
		)
		(fp_line
			(start -0.67945 -0.3048)
			(end -0.67945 0.3048)
			(stroke
				(width 0.1)
				(type default)
			)
			(layer "B.Fab")
		)
		(pad "1" smd circle
			(at 0.40005 0)
			(size 0 0)
			(layers "B.Cu" "B.Mask" "B.Paste")
			(net "P1V2_AUX")
		)
		(pad "2" smd circle
			(at -0.40005 0)
			(size 0 0)
			(layers "B.Cu" "B.Mask" "B.Paste")
			(net "GND")
		)
	)
)
